(kicad_pcb
	(version 20260206)
	(generator "pcbnew")
	(generator_version "10.0")
	(general
		(thickness 1.6)
		(legacy_teardrops no)
	)
	(paper "A4")
	(title_block
		(title "timecard-production-celestica-r4006 — R4006-B0001-02_R01.brd")
		(comment 1 "Time Appliance Project (Time Card) / footprints 916-919 of 1113")
	)
	(layers
		(0 "F.Cu" signal "TOP")
		(4 "In1.Cu" signal "L02_GND1")
		(6 "In2.Cu" signal "L03_SIG1")
		(8 "In3.Cu" signal "L04_GND2")
		(10 "In4.Cu" signal "L05_VCC1")
		(12 "In5.Cu" signal "L06_VCC2")
		(14 "In6.Cu" signal "L07_GND3")
		(16 "In7.Cu" signal "L08_SIG2")
		(18 "In8.Cu" signal "L09_GND4")
		(2 "B.Cu" signal "BOTTOM")
		(9 "F.Adhes" user "F.Adhesive")
		(11 "B.Adhes" user "B.Adhesive")
		(13 "F.Paste" user "Package Geometry/Pastemask Top")
		(15 "B.Paste" user "Package Geometry/Pastemask Bottom")
		(5 "F.SilkS" user "Ref Des/Silkscreen Top")
		(7 "B.SilkS" user "Ref Des/Silkscreen Bottom")
		(1 "F.Mask" user "Board Geometry/Soldermask Top")
		(3 "B.Mask" user "Board Geometry/Soldermask Bottom")
		(17 "Dwgs.User" user "User.Drawings")
		(19 "Cmts.User" user "User.Comments")
		(21 "Eco1.User" user "User.Eco1")
		(23 "Eco2.User" user "User.Eco2")
		(25 "Edge.Cuts" user "Board Geometry/Outline")
		(27 "Margin" user)
		(31 "F.CrtYd" user "Package Geometry/Place Bound Top")
		(29 "B.CrtYd" user "Package Geometry/Place Bound Bottom")
		(35 "F.Fab" user "Ref Des/Assembly Top")
		(33 "B.Fab" user "Ref Des/Assembly Bottom")
	)
	(footprint ""
		(layer "B.Cu")
		(at 18.8722 -23.6728 -90)
		(property "Reference" "R162"
			(at -3.2512 1.00457 270)
			(unlocked yes)
			(layer "B.SilkS")
			(effects
				(font
					(size 0.7874 0.5842)
					(thickness 0.1524)
				)
				(justify mirror)
			)
		)
		(property "Value" "VAL*"
			(at -0.02032 2.13233 270)
			(unlocked yes)
			(layer "B.Fab")
			(hide yes)
			(effects
				(font
					(size 0.7874 0.5842)
					(thickness 0.1524)
				)
				(justify mirror)
			)
		)
		(property "Tolerance" "TOL*"
			(at -0.044704 3.05435 270)
			(unlocked yes)
			(layer "Cmts.User")
			(hide yes)
			(effects
				(font
					(size 0.7874 0.5842)
					(thickness 0.1524)
				)
				(justify mirror)
			)
		)
		(property "User Part Number" "PARTNUM*"
			(at -0.02032 4.024884 270)
			(unlocked yes)
			(layer "Cmts.User")
			(hide yes)
			(effects
				(font
					(size 0.7874 0.5842)
					(thickness 0.1524)
				)
				(justify mirror)
			)
		)
		(property "Device Type" "RESISTOR-G155-14701-01,4.7KOHMA"
			(at -0.008382 1.210564 270)
			(unlocked yes)
			(layer "B.Fab")
			(hide yes)
			(effects
				(font
					(size 0.7874 0.5842)
					(thickness 0.1524)
				)
				(justify mirror)
			)
		)
		(duplicate_pad_numbers_are_jumpers no)
		(fp_line
			(start -1.143 0.5588)
			(end -1.143 -0.5588)
			(stroke
				(width 0.1)
				(type default)
			)
			(layer "B.SilkS")
		)
		(fp_line
			(start 1.143 0.5588)
			(end -1.143 0.5588)
			(stroke
				(width 0.1)
				(type default)
			)
			(layer "B.SilkS")
		)
		(fp_line
			(start -1.143 -0.5588)
			(end 1.143 -0.5588)
			(stroke
				(width 0.1)
				(type default)
			)
			(layer "B.SilkS")
		)
		(fp_line
			(start 1.143 -0.5588)
			(end 1.143 0.5588)
			(stroke
				(width 0.1)
				(type default)
			)
			(layer "B.SilkS")
		)
		(fp_rect
			(start -1.143 0.5588)
			(end 1.143 -0.5588)
			(stroke
				(width 0)
				(type default)
			)
			(fill no)
			(layer "B.CrtYd")
		)
		(fp_line
			(start -0.508 0.3048)
			(end -0.508 -0.3048)
			(stroke
				(width 0.1)
				(type default)
			)
			(layer "B.Fab")
		)
		(fp_line
			(start 0.508 0.3048)
			(end -0.508 0.3048)
			(stroke
				(width 0.1)
				(type default)
			)
			(layer "B.Fab")
		)
		(fp_line
			(start -0.508 -0.3048)
			(end 0.508 -0.3048)
			(stroke
				(width 0.1)
				(type default)
			)
			(layer "B.Fab")
		)
		(fp_line
			(start 0.508 -0.3048)
			(end 0.508 0.3048)
			(stroke
				(width 0.1)
				(type default)
			)
			(layer "B.Fab")
		)
		(pad "1" smd rect
			(at 0.5334 0 90)
			(size 0.7112 0.6096)
			(layers "B.Cu" "B.Mask" "B.Paste")
			(net "XP3R3V_FPGA")
		)
		(pad "2" smd rect
			(at -0.5334 0 90)
			(size 0.7112 0.6096)
			(layers "B.Cu" "B.Mask" "B.Paste")
			(net "UNNAMED_5_24LC16BTISTTSSOP8_I_2")
		)
		(zone
			(layer "B.Cu")
			(hatch none 0.5)
			(connect_pads
				(clearance 0)
			)
			(min_thickness 0.25)
			(keepout
				(tracks allowed)
				(vias not_allowed)
				(pads allowed)
				(copperpour not_allowed)
				(footprints allowed)
			)
			(placement
				(enabled no)
				(sheetname "")
			)
			(fill
				(thermal_gap 0.5)
				(thermal_bridge_width 0.5)
				(island_removal_mode 0)
			)
			(polygon
				(pts
					(xy 18.5674 -23.749) (xy 18.5674 -23.5966) (xy 19.177 -23.5966) (xy 19.177 -23.749)
				)
			)
		)
	)
	(footprint ""
		(layer "B.Cu")
		(at 86.233 -73.279 -90)
		(property "Reference" "R342"
			(at 3.556 0.16637 270)
			(unlocked yes)
			(layer "B.SilkS")
			(effects
				(font
					(size 0.7874 0.5842)
					(thickness 0.1524)
				)
				(justify mirror)
			)
		)
		(property "Value" "VAL*"
			(at -0.02032 2.13233 270)
			(unlocked yes)
			(layer "B.Fab")
			(hide yes)
			(effects
				(font
					(size 0.7874 0.5842)
					(thickness 0.1524)
				)
				(justify mirror)
			)
		)
		(property "Tolerance" "TOL*"
			(at -0.044704 3.05435 270)
			(unlocked yes)
			(layer "Cmts.User")
			(hide yes)
			(effects
				(font
					(size 0.7874 0.5842)
					(thickness 0.1524)
				)
				(justify mirror)
			)
		)
		(property "User Part Number" "PARTNUM*"
			(at -0.02032 4.024884 270)
			(unlocked yes)
			(layer "Cmts.User")
			(hide yes)
			(effects
				(font
					(size 0.7874 0.5842)
					(thickness 0.1524)
				)
				(justify mirror)
			)
		)
		(property "Device Type" "RESISTOR-G155-14701-01,4.7KOHMA"
			(at -0.008382 1.210564 270)
			(unlocked yes)
			(layer "B.Fab")
			(hide yes)
			(effects
				(font
					(size 0.7874 0.5842)
					(thickness 0.1524)
				)
				(justify mirror)
			)
		)
		(duplicate_pad_numbers_are_jumpers no)
		(fp_line
			(start -1.143 0.5588)
			(end -1.143 -0.5588)
			(stroke
				(width 0.1)
				(type default)
			)
			(layer "B.SilkS")
		)
		(fp_line
			(start 1.143 0.5588)
			(end -1.143 0.5588)
			(stroke
				(width 0.1)
				(type default)
			)
			(layer "B.SilkS")
		)
		(fp_line
			(start -1.143 -0.5588)
			(end 1.143 -0.5588)
			(stroke
				(width 0.1)
				(type default)
			)
			(layer "B.SilkS")
		)
		(fp_line
			(start 1.143 -0.5588)
			(end 1.143 0.5588)
			(stroke
				(width 0.1)
				(type default)
			)
			(layer "B.SilkS")
		)
		(fp_rect
			(start -1.143 0.5588)
			(end 1.143 -0.5588)
			(stroke
				(width 0)
				(type default)
			)
			(fill no)
			(layer "B.CrtYd")
		)
		(fp_line
			(start -0.508 0.3048)
			(end -0.508 -0.3048)
			(stroke
				(width 0.1)
				(type default)
			)
			(layer "B.Fab")
		)
		(fp_line
			(start 0.508 0.3048)
			(end -0.508 0.3048)
			(stroke
				(width 0.1)
				(type default)
			)
			(layer "B.Fab")
		)
		(fp_line
			(start -0.508 -0.3048)
			(end 0.508 -0.3048)
			(stroke
				(width 0.1)
				(type default)
			)
			(layer "B.Fab")
		)
		(fp_line
			(start 0.508 -0.3048)
			(end 0.508 0.3048)
			(stroke
				(width 0.1)
				(type default)
			)
			(layer "B.Fab")
		)
		(pad "1" smd rect
			(at 0.5334 0 90)
			(size 0.7112 0.6096)
			(layers "B.Cu" "B.Mask" "B.Paste")
			(net "XP3R3V_FPGA")
		)
		(pad "2" smd rect
			(at -0.5334 0 90)
			(size 0.7112 0.6096)
			(layers "B.Cu" "B.Mask" "B.Paste")
			(net "BNO080_EVN_SCL")
		)
		(zone
			(layer "B.Cu")
			(hatch none 0.5)
			(connect_pads
				(clearance 0)
			)
			(min_thickness 0.25)
			(keepout
				(tracks allowed)
				(vias not_allowed)
				(pads allowed)
				(copperpour not_allowed)
				(footprints allowed)
			)
			(placement
				(enabled no)
				(sheetname "")
			)
			(fill
				(thermal_gap 0.5)
				(thermal_bridge_width 0.5)
				(island_removal_mode 0)
			)
			(polygon
				(pts
					(xy 85.9282 -73.3552) (xy 85.9282 -73.2028) (xy 86.5378 -73.2028) (xy 86.5378 -73.3552)
				)
			)
		)
	)
	(footprint ""
		(layer "B.Cu")
		(at 32.131 -91.059 -90)
		(property "Reference" "C101"
			(at -3.175 -0.08763 270)
			(unlocked yes)
			(layer "B.SilkS")
			(effects
				(font
					(size 0.7874 0.5842)
					(thickness 0.1524)
				)
				(justify mirror)
			)
		)
		(property "Value" "VAL*"
			(at -0.0762 2.067306 270)
			(unlocked yes)
			(layer "B.Fab")
			(hide yes)
			(effects
				(font
					(size 0.7874 0.5842)
					(thickness 0.1524)
				)
				(justify mirror)
			)
		)
		(property "Tolerance" "TOL*"
			(at -0.0762 3.032506 270)
			(unlocked yes)
			(layer "Cmts.User")
			(hide yes)
			(effects
				(font
					(size 0.7874 0.5842)
					(thickness 0.1524)
				)
				(justify mirror)
			)
		)
		(property "User Part Number" "PARTNUM*"
			(at -0.1016 4.023106 270)
			(unlocked yes)
			(layer "Cmts.User")
			(hide yes)
			(effects
				(font
					(size 0.7874 0.5842)
					(thickness 0.1524)
				)
				(justify mirror)
			)
		)
		(property "Device Type" "CAPACITOR-G105-0B104-EK,0.1UF,A"
			(at -0.0508 1.127506 270)
			(unlocked yes)
			(layer "B.Fab")
			(hide yes)
			(effects
				(font
					(size 0.7874 0.5842)
					(thickness 0.1524)
				)
				(justify mirror)
			)
		)
		(duplicate_pad_numbers_are_jumpers no)
		(fp_line
			(start -1.143 0.5588)
			(end -1.143 -0.5588)
			(stroke
				(width 0.1)
				(type default)
			)
			(layer "B.SilkS")
		)
		(fp_line
			(start 1.143 0.5588)
			(end -1.143 0.5588)
			(stroke
				(width 0.1)
				(type default)
			)
			(layer "B.SilkS")
		)
		(fp_line
			(start -1.143 -0.5588)
			(end 1.143 -0.5588)
			(stroke
				(width 0.1)
				(type default)
			)
			(layer "B.SilkS")
		)
		(fp_line
			(start 1.143 -0.5588)
			(end 1.143 0.5588)
			(stroke
				(width 0.1)
				(type default)
			)
			(layer "B.SilkS")
		)
		(fp_poly
			(pts
				(xy 1.143 0.5588) (xy -1.143 0.5588) (xy -1.143 -0.5588) (xy 1.143 -0.5588)
			)
			(stroke
				(width 0)
				(type default)
			)
			(fill no)
			(layer "B.CrtYd")
		)
		(fp_line
			(start -0.508 0.3048)
			(end -0.508 -0.3048)
			(stroke
				(width 0.1)
				(type default)
			)
			(layer "B.Fab")
		)
		(fp_line
			(start 0.508 0.3048)
			(end -0.508 0.3048)
			(stroke
				(width 0.1)
				(type default)
			)
			(layer "B.Fab")
		)
		(fp_line
			(start -0.508 -0.3048)
			(end 0.508 -0.3048)
			(stroke
				(width 0.1)
				(type default)
			)
			(layer "B.Fab")
		)
		(fp_line
			(start 0.508 -0.3048)
			(end 0.508 0.3048)
			(stroke
				(width 0.1)
				(type default)
			)
			(layer "B.Fab")
		)
		(pad "1" smd rect
			(at 0.5334 0 90)
			(size 0.7112 0.6096)
			(layers "B.Cu" "B.Mask" "B.Paste")
			(net "XP3R3V_VPHY")
		)
		(pad "2" smd rect
			(at -0.5334 0 90)
			(size 0.7112 0.6096)
			(layers "B.Cu" "B.Mask" "B.Paste")
			(net "SG")
		)
		(zone
			(layer "B.Cu")
			(hatch none 0.5)
			(connect_pads
				(clearance 0)
			)
			(min_thickness 0.25)
			(keepout
				(tracks allowed)
				(vias not_allowed)
				(pads allowed)
				(copperpour not_allowed)
				(footprints allowed)
			)
			(placement
				(enabled no)
				(sheetname "")
			)
			(fill
				(thermal_gap 0.5)
				(thermal_bridge_width 0.5)
				(island_removal_mode 0)
			)
			(polygon
				(pts
					(xy 31.8262 -90.9828) (xy 32.4358 -90.9828) (xy 32.4358 -91.1352) (xy 31.8262 -91.1352)
				)
			)
		)
		(zone
			(layer "B.Cu")
			(hatch none 0.5)
			(connect_pads
				(clearance 0)
			)
			(min_thickness 0.25)
			(keepout
				(tracks not_allowed)
				(vias allowed)
				(pads allowed)
				(copperpour not_allowed)
				(footprints allowed)
			)
			(placement
				(enabled no)
				(sheetname "")
			)
			(fill
				(thermal_gap 0.5)
				(thermal_bridge_width 0.5)
				(island_removal_mode 0)
			)
			(polygon
				(pts
					(xy 31.8262 -90.9828) (xy 32.4358 -90.9828) (xy 32.4358 -91.1352) (xy 31.8262 -91.1352)
				)
			)
		)
	)
	(footprint ""
		(layer "B.Cu")
		(at 11.684 -75.946)
		(property "Reference" "U8"
			(at 1.27 2.83337 0)
			(unlocked yes)
			(layer "B.SilkS")
			(effects
				(font
					(size 0.7874 0.5842)
					(thickness 0.1524)
				)
				(justify mirror)
			)
		)
		(property "Value" ""
			(at 0 0 0)
			(layer "B.Fab")
			(effects
				(font
					(size 1.27 1.27)
				)
				(justify mirror)
			)
		)
		(property "Device Type" "LM75BDP_TSSOP8-G220-10215-01"
			(at 0.03175 2.55651 0)
			(unlocked yes)
			(layer "B.Fab")
			(hide yes)
			(effects
				(font
					(size 0.7874 0.5842)
					(thickness 0.1524)
				)
				(justify mirror)
			)
		)
		(property "User Part Number" "PARTNUM*"
			(at 0.037592 3.488182 0)
			(unlocked yes)
			(layer "Cmts.User")
			(hide yes)
			(effects
				(font
					(size 0.7874 0.5842)
					(thickness 0.1524)
				)
				(justify mirror)
			)
		)
		(duplicate_pad_numbers_are_jumpers no)
		(fp_line
			(start -3.3147 -1.45796)
			(end -1.778 -1.45796)
			(stroke
				(width 0.1)
				(type default)
			)
			(layer "B.SilkS")
		)
		(fp_line
			(start -3.3147 1.45796)
			(end -3.3147 -1.45796)
			(stroke
				(width 0.1)
				(type default)
			)
			(layer "B.SilkS")
		)
		(fp_line
			(start -1.778 -1.778)
			(end 1.778 -1.778)
			(stroke
				(width 0.1)
				(type default)
			)
			(layer "B.SilkS")
		)
		(fp_line
			(start -1.778 -1.45796)
			(end -1.778 -1.778)
			(stroke
				(width 0.1)
				(type default)
			)
			(layer "B.SilkS")
		)
		(fp_line
			(start -1.778 1.45796)
			(end -3.3147 1.45796)
			(stroke
				(width 0.1)
				(type default)
			)
			(layer "B.SilkS")
		)
		(fp_line
			(start -1.778 1.778)
			(end -1.778 1.45796)
			(stroke
				(width 0.1)
				(type default)
			)
			(layer "B.SilkS")
		)
		(fp_line
			(start 1.778 -1.778)
			(end 1.778 -1.45796)
			(stroke
				(width 0.1)
				(type default)
			)
			(layer "B.SilkS")
		)
		(fp_line
			(start 1.778 -1.45796)
			(end 3.3147 -1.45796)
			(stroke
				(width 0.1)
				(type default)
			)
			(layer "B.SilkS")
		)
		(fp_line
			(start 1.778 1.45796)
			(end 1.778 1.778)
			(stroke
				(width 0.1)
				(type default)
			)
			(layer "B.SilkS")
		)
		(fp_line
			(start 1.778 1.778)
			(end -1.778 1.778)
			(stroke
				(width 0.1)
				(type default)
			)
			(layer "B.SilkS")
		)
		(fp_line
			(start 3.3147 -1.45796)
			(end 3.3147 1.45796)
			(stroke
				(width 0.1)
				(type default)
			)
			(layer "B.SilkS")
		)
		(fp_line
			(start 3.3147 1.45796)
			(end 1.778 1.45796)
			(stroke
				(width 0.1)
				(type default)
			)
			(layer "B.SilkS")
		)
		(fp_poly
			(pts
				(arc
					(start 3.77952 -2.15392)
					(mid 3.01752 -2.15392)
					(end 3.77952 -2.15392)
				)
			)
			(stroke
				(width 0)
				(type default)
			)
			(fill yes)
			(layer "B.SilkS")
		)
		(fp_rect
			(start 3.5687 -2.032)
			(end -3.5687 2.032)
			(stroke
				(width 0)
				(type default)
			)
			(fill no)
			(layer "B.CrtYd")
		)
		(fp_line
			(start -1.524 -1.524)
			(end -1.524 1.524)
			(stroke
				(width 0.1)
				(type default)
			)
			(layer "B.Fab")
		)
		(fp_line
			(start -1.524 1.524)
			(end 1.524 1.524)
			(stroke
				(width 0.1)
				(type default)
			)
			(layer "B.Fab")
		)
		(fp_line
			(start 1.524 -1.524)
			(end -1.524 -1.524)
			(stroke
				(width 0.1)
				(type default)
			)
			(layer "B.Fab")
		)
		(fp_line
			(start 1.524 1.524)
			(end 1.524 -1.524)
			(stroke
				(width 0.1)
				(type default)
			)
			(layer "B.Fab")
		)
		(fp_poly
			(pts
				(arc
					(start 1.3716 -0.9398)
					(mid 0.6096 -0.9398)
					(end 1.3716 -0.9398)
				)
			)
			(stroke
				(width 0)
				(type default)
			)
			(fill yes)
			(layer "B.Fab")
		)
		(fp_text user "8"
			(at -3.81 -1.35763 0)
			(unlocked yes)
			(layer "B.SilkS")
			(effects
				(font
					(size 0.7874 0.5842)
					(thickness 0.1524)
				)
				(justify mirror)
			)
		)
		(fp_text user "5"
			(at -3.683 1.05537 0)
			(unlocked yes)
			(layer "B.SilkS")
			(effects
				(font
					(size 0.7874 0.5842)
					(thickness 0.1524)
				)
				(justify mirror)
			)
		)
		(fp_text user "4"
			(at 3.81 0.80137 0)
			(unlocked yes)
			(layer "B.SilkS")
			(effects
				(font
					(size 0.7874 0.5842)
					(thickness 0.1524)
				)
				(justify mirror)
			)
		)
		(fp_text user "8"
			(at -2.3368 -1.429258 0)
			(unlocked yes)
			(layer "B.Fab")
			(effects
				(font
					(size 0.7874 0.5842)
					(thickness 0.1524)
				)
				(justify mirror)
			)
		)
		(fp_text user "5"
			(at -2.0828 1.237742 0)
			(unlocked yes)
			(layer "B.Fab")
			(effects
				(font
					(size 0.7874 0.5842)
					(thickness 0.1524)
				)
				(justify mirror)
			)
		)
		(fp_text user "4"
			(at 2.1082 1.110742 0)
			(unlocked yes)
			(layer "B.Fab")
			(effects
				(font
					(size 0.7874 0.5842)
					(thickness 0.1524)
				)
				(justify mirror)
			)
		)
		(pad "1" smd rect
			(at 2.2987 -0.97536 90)
			(size 0.4572 1.524)
			(layers "B.Cu" "B.Mask" "B.Paste")
			(net "R_LM75B_1_I2C_SDA")
		)
		(pad "2" smd rect
			(at 2.2987 -0.32512 90)
			(size 0.4572 1.524)
			(layers "B.Cu" "B.Mask" "B.Paste")
			(net "LM75B_I2C_SCL")
		)
		(pad "3" smd rect
			(at 2.2987 0.32512 90)
			(size 0.4572 1.524)
			(layers "B.Cu" "B.Mask" "B.Paste")
			(net "FPGA_IN_LM75B_INT1_N")
		)
		(pad "4" smd rect
			(at 2.2987 0.97536 90)
			(size 0.4572 1.524)
			(layers "B.Cu" "B.Mask" "B.Paste")
			(net "SG")
		)
		(pad "5" smd rect
			(at -2.2987 0.97536 90)
			(size 0.4572 1.524)
			(layers "B.Cu" "B.Mask" "B.Paste")
			(net "UNNAMED_6_LM75BDPTSSOP8_I34_A2")
		)
		(pad "6" smd rect
			(at -2.2987 0.32512 90)
			(size 0.4572 1.524)
			(layers "B.Cu" "B.Mask" "B.Paste")
			(net "UNNAMED_6_LM75BDPTSSOP8_I34_A1")
		)
		(pad "7" smd rect
			(at -2.2987 -0.32512 90)
			(size 0.4572 1.524)
			(layers "B.Cu" "B.Mask" "B.Paste")
			(net "UNNAMED_6_LM75BDPTSSOP8_I34_A0")
		)
		(pad "8" smd rect
			(at -2.2987 -0.97536 90)
			(size 0.4572 1.524)
			(layers "B.Cu" "B.Mask" "B.Paste")
			(net "XP3R3V_FPGA")
		)
	)
)
